(kicad_pcb
	(version 20260206)
	(generator "pcbnew")
	(generator_version "10.0")
	(general
		(thickness 1.6)
		(legacy_teardrops no)
	)
	(paper "A4")
	(title_block
		(title "peb — Lightning_PEB_BRD.brd")
		(comment 1 "Lightning (Wiwynn / Facebook NVMe JBOF) / footprints 1182-1188 of 2563")
	)
	(layers
		(0 "F.Cu" signal "TOP")
		(4 "In1.Cu" signal "L2GND")
		(6 "In2.Cu" signal "L3")
		(8 "In3.Cu" signal "L4VCC")
		(10 "In4.Cu" signal "L5VCC")
		(12 "In5.Cu" signal "L6")
		(14 "In6.Cu" signal "L7GND")
		(2 "B.Cu" signal "BOTTOM")
		(9 "F.Adhes" user "F.Adhesive")
		(11 "B.Adhes" user "B.Adhesive")
		(13 "F.Paste" user "Package Geometry/Pastemask Top")
		(15 "B.Paste" user "Package Geometry/Pastemask Bottom")
		(5 "F.SilkS" user "Ref Des/Silkscreen Top")
		(7 "B.SilkS" user "Ref Des/Silkscreen Bottom")
		(1 "F.Mask" user "Board Geometry/Soldermask Top")
		(3 "B.Mask" user "Board Geometry/Soldermask Bottom")
		(17 "Dwgs.User" user "User.Drawings")
		(19 "Cmts.User" user "User.Comments")
		(21 "Eco1.User" user "User.Eco1")
		(23 "Eco2.User" user "User.Eco2")
		(25 "Edge.Cuts" user "Board Geometry/Outline")
		(27 "Margin" user)
		(31 "F.CrtYd" user "Package Geometry/Place Bound Top")
		(29 "B.CrtYd" user "Package Geometry/Place Bound Bottom")
		(35 "F.Fab" user "Ref Des/Assembly Top")
		(33 "B.Fab" user "Ref Des/Assembly Bottom")
	)
	(footprint ""
		(layer "F.Cu")
		(at 63.9318 -112.5982 -90)
		(property "Reference" "R439"
			(at 0 0 270)
			(layer "F.SilkS")
			(hide yes)
			(effects
				(font
					(size 1.27 1.27)
				)
			)
		)
		(property "Value" "4K7R2F-GP"
			(at 0.064008 -3.993896 270)
			(unlocked yes)
			(layer "F.Fab")
			(hide yes)
			(effects
				(font
					(size 1.016 1.016)
					(thickness 0.1524)
				)
			)
		)
		(property "Device Type" "R402H16"
			(at 0.064008 -5.517896 270)
			(unlocked yes)
			(layer "F.Fab")
			(hide yes)
			(effects
				(font
					(size 1.016 1.016)
					(thickness 0.1524)
				)
			)
		)
		(duplicate_pad_numbers_are_jumpers no)
		(fp_line
			(start -0.508 -0.9398)
			(end -0.508 0.9398)
			(stroke
				(width 0.1524)
				(type default)
			)
			(layer "F.SilkS")
		)
		(fp_line
			(start 0.508 -0.9398)
			(end -0.508 -0.9398)
			(stroke
				(width 0.1524)
				(type default)
			)
			(layer "F.SilkS")
		)
		(fp_rect
			(start -0.508 0.9398)
			(end 0.508 -0.9398)
			(stroke
				(width 0)
				(type default)
			)
			(fill no)
			(layer "F.CrtYd")
		)
		(fp_rect
			(start -0.508 0.9398)
			(end 0.508 -0.9398)
			(stroke
				(width 0)
				(type default)
			)
			(fill no)
			(layer "F.Fab")
		)
		(pad "1" smd custom
			(at 0 -0.4445 270)
			(size 0.1397 0.1397)
			(layers "F.Cu" "F.Mask" "F.Paste")
			(net "BMC_I2C11_MINI5_SDA_S")
			(options
				(clearance outline)
				(anchor circle)
			)
			(primitives
				(gr_poly
					(pts
						(arc
							(start -0.1778 -0.2794)
							(mid -0.249642 -0.249642)
							(end -0.2794 -0.1778)
						)
						(arc
							(start -0.2794 0.1778)
							(mid -0.249642 0.249642)
							(end -0.1778 0.2794)
						)
						(arc
							(start 0.1778 0.2794)
							(mid 0.249642 0.249642)
							(end 0.2794 0.1778)
						)
						(arc
							(start 0.2794 -0.1778)
							(mid 0.249642 -0.249642)
							(end 0.1778 -0.2794)
						)
					)
					(width 0)
					(fill yes)
				)
			)
		)
		(pad "2" smd custom
			(at 0 0.4445 270)
			(size 0.1397 0.1397)
			(layers "F.Cu" "F.Mask" "F.Paste")
			(net "P3V3_STBY")
			(options
				(clearance outline)
				(anchor circle)
			)
			(primitives
				(gr_poly
					(pts
						(arc
							(start -0.1778 -0.2794)
							(mid -0.249642 -0.249642)
							(end -0.2794 -0.1778)
						)
						(arc
							(start -0.2794 0.1778)
							(mid -0.249642 0.249642)
							(end -0.1778 0.2794)
						)
						(arc
							(start 0.1778 0.2794)
							(mid 0.249642 0.249642)
							(end 0.2794 0.1778)
						)
						(arc
							(start 0.2794 -0.1778)
							(mid 0.249642 -0.249642)
							(end 0.1778 -0.2794)
						)
					)
					(width 0)
					(fill yes)
				)
			)
		)
	)
	(footprint ""
		(layer "F.Cu")
		(at 201.1172 -7.0104 180)
		(property "Reference" "R25"
			(at 0 0 180)
			(layer "F.SilkS")
			(hide yes)
			(effects
				(font
					(size 1.27 1.27)
				)
			)
		)
		(property "Value" "4K7R2F-GP"
			(at 0.064008 -3.993896 180)
			(unlocked yes)
			(layer "F.Fab")
			(hide yes)
			(effects
				(font
					(size 1.016 1.016)
					(thickness 0.1524)
				)
			)
		)
		(property "Device Type" "R402H16"
			(at 0.064008 -5.517896 180)
			(unlocked yes)
			(layer "F.Fab")
			(hide yes)
			(effects
				(font
					(size 1.016 1.016)
					(thickness 0.1524)
				)
			)
		)
		(duplicate_pad_numbers_are_jumpers no)
		(fp_line
			(start 0.508 -0.9398)
			(end -0.508 -0.9398)
			(stroke
				(width 0.1524)
				(type default)
			)
			(layer "F.SilkS")
		)
		(fp_line
			(start -0.508 -0.9398)
			(end -0.508 0.9398)
			(stroke
				(width 0.1524)
				(type default)
			)
			(layer "F.SilkS")
		)
		(fp_rect
			(start -0.508 0.9398)
			(end 0.508 -0.9398)
			(stroke
				(width 0)
				(type default)
			)
			(fill no)
			(layer "F.CrtYd")
		)
		(fp_rect
			(start -0.508 0.9398)
			(end 0.508 -0.9398)
			(stroke
				(width 0)
				(type default)
			)
			(fill no)
			(layer "F.Fab")
		)
		(pad "1" smd custom
			(at 0 -0.4445 180)
			(size 0.1397 0.1397)
			(layers "F.Cu" "F.Mask" "F.Paste")
			(net "BOOT_RECOVERY_0")
			(options
				(clearance outline)
				(anchor circle)
			)
			(primitives
				(gr_poly
					(pts
						(arc
							(start -0.1778 -0.2794)
							(mid -0.249642 -0.249642)
							(end -0.2794 -0.1778)
						)
						(arc
							(start -0.2794 0.1778)
							(mid -0.249642 0.249642)
							(end -0.1778 0.2794)
						)
						(arc
							(start 0.1778 0.2794)
							(mid 0.249642 0.249642)
							(end 0.2794 0.1778)
						)
						(arc
							(start 0.2794 -0.1778)
							(mid 0.249642 -0.249642)
							(end 0.1778 -0.2794)
						)
					)
					(width 0)
					(fill yes)
				)
			)
		)
		(pad "2" smd custom
			(at 0 0.4445 180)
			(size 0.1397 0.1397)
			(layers "F.Cu" "F.Mask" "F.Paste")
			(net "GND")
			(options
				(clearance outline)
				(anchor circle)
			)
			(primitives
				(gr_poly
					(pts
						(arc
							(start -0.1778 -0.2794)
							(mid -0.249642 -0.249642)
							(end -0.2794 -0.1778)
						)
						(arc
							(start -0.2794 0.1778)
							(mid -0.249642 0.249642)
							(end -0.1778 0.2794)
						)
						(arc
							(start 0.1778 0.2794)
							(mid 0.249642 0.249642)
							(end 0.2794 0.1778)
						)
						(arc
							(start 0.2794 -0.1778)
							(mid 0.249642 -0.249642)
							(end 0.1778 -0.2794)
						)
					)
					(width 0)
					(fill yes)
				)
			)
		)
	)
	(footprint ""
		(layer "F.Cu")
		(at 206.392018 -212.420454 180)
		(property "Reference" "C113"
			(at 0 0 180)
			(layer "F.SilkS")
			(hide yes)
			(effects
				(font
					(size 1.27 1.27)
				)
			)
		)
		(property "Value" "SCD22U10V2KX-1GP"
			(at 1.1811 -2.7051 180)
			(unlocked yes)
			(layer "F.Fab")
			(hide yes)
			(effects
				(font
					(size 1.016 1.016)
					(thickness 0.1524)
				)
			)
		)
		(property "Device Type" "C402H22"
			(at 1.1811 -4.2291 180)
			(unlocked yes)
			(layer "F.Fab")
			(hide yes)
			(effects
				(font
					(size 1.016 1.016)
					(thickness 0.1524)
				)
			)
		)
		(duplicate_pad_numbers_are_jumpers no)
		(fp_rect
			(start -0.4318 0.9525)
			(end 0.4318 -0.9525)
			(stroke
				(width 0)
				(type default)
			)
			(fill no)
			(layer "F.CrtYd")
		)
		(fp_rect
			(start -0.4318 0.9525)
			(end 0.4318 -0.9525)
			(stroke
				(width 0)
				(type default)
			)
			(fill no)
			(layer "F.Fab")
		)
		(pad "1" smd custom
			(at 0 -0.4445 180)
			(size 0.1524 0.1524)
			(layers "F.Cu" "F.Mask" "F.Paste")
			(net "PCIE_TX_CAP_P40")
			(options
				(clearance outline)
				(anchor circle)
			)
			(primitives
				(gr_poly
					(pts
						(arc
							(start 0.3048 -0.2032)
							(mid 0.275042 -0.275042)
							(end 0.2032 -0.3048)
						)
						(arc
							(start -0.2032 -0.3048)
							(mid -0.275042 -0.275042)
							(end -0.3048 -0.2032)
						)
						(arc
							(start -0.3048 0.2032)
							(mid -0.275042 0.275042)
							(end -0.2032 0.3048)
						)
						(arc
							(start 0.2032 0.3048)
							(mid 0.275042 0.275042)
							(end 0.3048 0.2032)
						)
					)
					(width 0)
					(fill yes)
				)
			)
		)
		(pad "2" smd custom
			(at 0 0.4445 180)
			(size 0.1524 0.1524)
			(layers "F.Cu" "F.Mask" "F.Paste")
			(net "PCIE_TX_P40")
			(options
				(clearance outline)
				(anchor circle)
			)
			(primitives
				(gr_poly
					(pts
						(arc
							(start 0.3048 -0.2032)
							(mid 0.275042 -0.275042)
							(end 0.2032 -0.3048)
						)
						(arc
							(start -0.2032 -0.3048)
							(mid -0.275042 -0.275042)
							(end -0.3048 -0.2032)
						)
						(arc
							(start -0.3048 0.2032)
							(mid -0.275042 0.275042)
							(end -0.2032 0.3048)
						)
						(arc
							(start 0.2032 0.3048)
							(mid 0.275042 0.275042)
							(end 0.3048 0.2032)
						)
					)
					(width 0)
					(fill yes)
				)
			)
		)
	)
	(footprint ""
		(layer "F.Cu")
		(at 159.350202 -58.447432 180)
		(property "Reference" "PR176"
			(at 0 0 180)
			(layer "F.SilkS")
			(hide yes)
			(effects
				(font
					(size 1.27 1.27)
				)
			)
		)
		(property "Value" "100KR2F-L1-GP"
			(at 0.064008 -3.993896 180)
			(unlocked yes)
			(layer "F.Fab")
			(hide yes)
			(effects
				(font
					(size 1.016 1.016)
					(thickness 0.1524)
				)
			)
		)
		(property "Device Type" "R402H16"
			(at 0.064008 -5.517896 180)
			(unlocked yes)
			(layer "F.Fab")
			(hide yes)
			(effects
				(font
					(size 1.016 1.016)
					(thickness 0.1524)
				)
			)
		)
		(duplicate_pad_numbers_are_jumpers no)
		(fp_line
			(start 0.508 -0.9398)
			(end -0.508 -0.9398)
			(stroke
				(width 0.1524)
				(type default)
			)
			(layer "F.SilkS")
		)
		(fp_line
			(start -0.508 -0.9398)
			(end -0.508 0.9398)
			(stroke
				(width 0.1524)
				(type default)
			)
			(layer "F.SilkS")
		)
		(fp_rect
			(start -0.508 0.9398)
			(end 0.508 -0.9398)
			(stroke
				(width 0)
				(type default)
			)
			(fill no)
			(layer "F.CrtYd")
		)
		(fp_rect
			(start -0.508 0.9398)
			(end 0.508 -0.9398)
			(stroke
				(width 0)
				(type default)
			)
			(fill no)
			(layer "F.Fab")
		)
		(pad "1" smd custom
			(at 0 -0.4445 180)
			(size 0.1397 0.1397)
			(layers "F.Cu" "F.Mask" "F.Paste")
			(net "P12V")
			(options
				(clearance outline)
				(anchor circle)
			)
			(primitives
				(gr_poly
					(pts
						(arc
							(start -0.1778 -0.2794)
							(mid -0.249642 -0.249642)
							(end -0.2794 -0.1778)
						)
						(arc
							(start -0.2794 0.1778)
							(mid -0.249642 0.249642)
							(end -0.1778 0.2794)
						)
						(arc
							(start 0.1778 0.2794)
							(mid 0.249642 0.249642)
							(end 0.2794 0.1778)
						)
						(arc
							(start 0.2794 -0.1778)
							(mid 0.249642 -0.249642)
							(end 0.1778 -0.2794)
						)
					)
					(width 0)
					(fill yes)
				)
			)
		)
		(pad "2" smd custom
			(at 0 0.4445 180)
			(size 0.1397 0.1397)
			(layers "F.Cu" "F.Mask" "F.Paste")
			(net "P0V9_EN")
			(options
				(clearance outline)
				(anchor circle)
			)
			(primitives
				(gr_poly
					(pts
						(arc
							(start -0.1778 -0.2794)
							(mid -0.249642 -0.249642)
							(end -0.2794 -0.1778)
						)
						(arc
							(start -0.2794 0.1778)
							(mid -0.249642 0.249642)
							(end -0.1778 0.2794)
						)
						(arc
							(start 0.1778 0.2794)
							(mid 0.249642 0.249642)
							(end 0.2794 0.1778)
						)
						(arc
							(start 0.2794 -0.1778)
							(mid 0.249642 -0.249642)
							(end 0.1778 -0.2794)
						)
					)
					(width 0)
					(fill yes)
				)
			)
		)
	)
	(footprint ""
		(layer "F.Cu")
		(at 53.721 -137.795 90)
		(property "Reference" "R153"
			(at 0 0 90)
			(layer "F.SilkS")
			(hide yes)
			(effects
				(font
					(size 1.27 1.27)
				)
			)
		)
		(property "Value" "4K7R2F-GP"
			(at 0.064008 -3.993896 90)
			(unlocked yes)
			(layer "F.Fab")
			(hide yes)
			(effects
				(font
					(size 1.016 1.016)
					(thickness 0.1524)
				)
			)
		)
		(property "Device Type" "R402H16"
			(at 0.064008 -5.517896 90)
			(unlocked yes)
			(layer "F.Fab")
			(hide yes)
			(effects
				(font
					(size 1.016 1.016)
					(thickness 0.1524)
				)
			)
		)
		(duplicate_pad_numbers_are_jumpers no)
		(fp_line
			(start 0.508 -0.9398)
			(end -0.508 -0.9398)
			(stroke
				(width 0.1524)
				(type default)
			)
			(layer "F.SilkS")
		)
		(fp_line
			(start -0.508 -0.9398)
			(end -0.508 0.9398)
			(stroke
				(width 0.1524)
				(type default)
			)
			(layer "F.SilkS")
		)
		(fp_rect
			(start -0.508 0.9398)
			(end 0.508 -0.9398)
			(stroke
				(width 0)
				(type default)
			)
			(fill no)
			(layer "F.CrtYd")
		)
		(fp_rect
			(start -0.508 0.9398)
			(end 0.508 -0.9398)
			(stroke
				(width 0)
				(type default)
			)
			(fill no)
			(layer "F.Fab")
		)
		(pad "1" smd custom
			(at 0 -0.4445 90)
			(size 0.1397 0.1397)
			(layers "F.Cu" "F.Mask" "F.Paste")
			(net "CBL_PRSNT_N_4")
			(options
				(clearance outline)
				(anchor circle)
			)
			(primitives
				(gr_poly
					(pts
						(arc
							(start -0.1778 -0.2794)
							(mid -0.249642 -0.249642)
							(end -0.2794 -0.1778)
						)
						(arc
							(start -0.2794 0.1778)
							(mid -0.249642 0.249642)
							(end -0.1778 0.2794)
						)
						(arc
							(start 0.1778 0.2794)
							(mid 0.249642 0.249642)
							(end 0.2794 0.1778)
						)
						(arc
							(start 0.2794 -0.1778)
							(mid 0.249642 -0.249642)
							(end 0.1778 -0.2794)
						)
					)
					(width 0)
					(fill yes)
				)
			)
		)
		(pad "2" smd custom
			(at 0 0.4445 90)
			(size 0.1397 0.1397)
			(layers "F.Cu" "F.Mask" "F.Paste")
			(net "P3V3_STBY")
			(options
				(clearance outline)
				(anchor circle)
			)
			(primitives
				(gr_poly
					(pts
						(arc
							(start -0.1778 -0.2794)
							(mid -0.249642 -0.249642)
							(end -0.2794 -0.1778)
						)
						(arc
							(start -0.2794 0.1778)
							(mid -0.249642 0.249642)
							(end -0.1778 0.2794)
						)
						(arc
							(start 0.1778 0.2794)
							(mid 0.249642 0.249642)
							(end 0.2794 0.1778)
						)
						(arc
							(start 0.2794 -0.1778)
							(mid 0.249642 -0.249642)
							(end 0.1778 -0.2794)
						)
					)
					(width 0)
					(fill yes)
				)
			)
		)
	)
	(footprint ""
		(layer "F.Cu")
		(at 20.6502 -191.4398 90)
		(property "Reference" "R2109"
			(at 0 0 90)
			(layer "F.SilkS")
			(hide yes)
			(effects
				(font
					(size 1.27 1.27)
				)
			)
		)
		(property "Value" "6K04R2F-GP"
			(at 0.064008 -3.993896 90)
			(unlocked yes)
			(layer "F.Fab")
			(hide yes)
			(effects
				(font
					(size 1.016 1.016)
					(thickness 0.1524)
				)
			)
		)
		(property "Device Type" "R402H16"
			(at 0.064008 -5.517896 90)
			(unlocked yes)
			(layer "F.Fab")
			(hide yes)
			(effects
				(font
					(size 1.016 1.016)
					(thickness 0.1524)
				)
			)
		)
		(duplicate_pad_numbers_are_jumpers no)
		(fp_line
			(start 0.508 -0.9398)
			(end -0.508 -0.9398)
			(stroke
				(width 0.1524)
				(type default)
			)
			(layer "F.SilkS")
		)
		(fp_line
			(start -0.508 -0.9398)
			(end -0.508 0.9398)
			(stroke
				(width 0.1524)
				(type default)
			)
			(layer "F.SilkS")
		)
		(fp_rect
			(start -0.508 0.9398)
			(end 0.508 -0.9398)
			(stroke
				(width 0)
				(type default)
			)
			(fill no)
			(layer "F.CrtYd")
		)
		(fp_rect
			(start -0.508 0.9398)
			(end 0.508 -0.9398)
			(stroke
				(width 0)
				(type default)
			)
			(fill no)
			(layer "F.Fab")
		)
		(pad "1" smd custom
			(at 0 -0.4445 90)
			(size 0.1397 0.1397)
			(layers "F.Cu" "F.Mask" "F.Paste")
			(net "MB0_CM_UV_R")
			(options
				(clearance outline)
				(anchor circle)
			)
			(primitives
				(gr_poly
					(pts
						(arc
							(start -0.1778 -0.2794)
							(mid -0.249642 -0.249642)
							(end -0.2794 -0.1778)
						)
						(arc
							(start -0.2794 0.1778)
							(mid -0.249642 0.249642)
							(end -0.1778 0.2794)
						)
						(arc
							(start 0.1778 0.2794)
							(mid 0.249642 0.249642)
							(end 0.2794 0.1778)
						)
						(arc
							(start 0.2794 -0.1778)
							(mid 0.249642 -0.249642)
							(end 0.1778 -0.2794)
						)
					)
					(width 0)
					(fill yes)
				)
			)
		)
		(pad "2" smd custom
			(at 0 0.4445 90)
			(size 0.1397 0.1397)
			(layers "F.Cu" "F.Mask" "F.Paste")
			(net "AGND_CURRENT_MON")
			(options
				(clearance outline)
				(anchor circle)
			)
			(primitives
				(gr_poly
					(pts
						(arc
							(start -0.1778 -0.2794)
							(mid -0.249642 -0.249642)
							(end -0.2794 -0.1778)
						)
						(arc
							(start -0.2794 0.1778)
							(mid -0.249642 0.249642)
							(end -0.1778 0.2794)
						)
						(arc
							(start 0.1778 0.2794)
							(mid 0.249642 0.249642)
							(end 0.2794 0.1778)
						)
						(arc
							(start 0.2794 -0.1778)
							(mid 0.249642 -0.249642)
							(end 0.1778 -0.2794)
						)
					)
					(width 0)
					(fill yes)
				)
			)
		)
	)
	(footprint ""
		(layer "F.Cu")
		(at 14.5034 -180.0606 -90)
		(property "Reference" "R1227"
			(at 0 0 270)
			(layer "F.SilkS")
			(hide yes)
			(effects
				(font
					(size 1.27 1.27)
				)
			)
		)
		(property "Value" "100KR2F-L1-GP"
			(at 0.064008 -3.993896 270)
			(unlocked yes)
			(layer "F.Fab")
			(hide yes)
			(effects
				(font
					(size 1.016 1.016)
					(thickness 0.1524)
				)
			)
		)
		(property "Device Type" "R402H16"
			(at 0.064008 -5.517896 270)
			(unlocked yes)
			(layer "F.Fab")
			(hide yes)
			(effects
				(font
					(size 1.016 1.016)
					(thickness 0.1524)
				)
			)
		)
		(duplicate_pad_numbers_are_jumpers no)
		(fp_line
			(start -0.508 -0.9398)
			(end -0.508 0.9398)
			(stroke
				(width 0.1524)
				(type default)
			)
			(layer "F.SilkS")
		)
		(fp_line
			(start 0.508 -0.9398)
			(end -0.508 -0.9398)
			(stroke
				(width 0.1524)
				(type default)
			)
			(layer "F.SilkS")
		)
		(fp_rect
			(start -0.508 0.9398)
			(end 0.508 -0.9398)
			(stroke
				(width 0)
				(type default)
			)
			(fill no)
			(layer "F.CrtYd")
		)
		(fp_rect
			(start -0.508 0.9398)
			(end 0.508 -0.9398)
			(stroke
				(width 0)
				(type default)
			)
			(fill no)
			(layer "F.Fab")
		)
		(pad "1" smd custom
			(at 0 -0.4445 270)
			(size 0.1397 0.1397)
			(layers "F.Cu" "F.Mask" "F.Paste")
			(net "P12V")
			(options
				(clearance outline)
				(anchor circle)
			)
			(primitives
				(gr_poly
					(pts
						(arc
							(start -0.1778 -0.2794)
							(mid -0.249642 -0.249642)
							(end -0.2794 -0.1778)
						)
						(arc
							(start -0.2794 0.1778)
							(mid -0.249642 0.249642)
							(end -0.1778 0.2794)
						)
						(arc
							(start 0.1778 0.2794)
							(mid 0.249642 0.249642)
							(end 0.2794 0.1778)
						)
						(arc
							(start 0.2794 -0.1778)
							(mid 0.249642 -0.249642)
							(end 0.1778 -0.2794)
						)
					)
					(width 0)
					(fill yes)
				)
			)
		)
		(pad "2" smd custom
			(at 0 0.4445 270)
			(size 0.1397 0.1397)
			(layers "F.Cu" "F.Mask" "F.Paste")
			(net "MB0_P12V_PWGIN_R")
			(options
				(clearance outline)
				(anchor circle)
			)
			(primitives
				(gr_poly
					(pts
						(arc
							(start -0.1778 -0.2794)
							(mid -0.249642 -0.249642)
							(end -0.2794 -0.1778)
						)
						(arc
							(start -0.2794 0.1778)
							(mid -0.249642 0.249642)
							(end -0.1778 0.2794)
						)
						(arc
							(start 0.1778 0.2794)
							(mid 0.249642 0.249642)
							(end 0.2794 0.1778)
						)
						(arc
							(start 0.2794 -0.1778)
							(mid 0.249642 -0.249642)
							(end 0.1778 -0.2794)
						)
					)
					(width 0)
					(fill yes)
				)
			)
		)
	)
)
